(kicad_pcb
	(version 20260206)
	(generator "pcbnew")
	(generator_version "10.0")
	(general
		(thickness 1.6)
		(legacy_teardrops no)
	)
	(paper "A4")
	(title_block
		(title "04192023_DAF0TMB3IC0_F0TG_MB_C_brd_V02_OCP.brd")
		(comment 1 "Grand Teton / footprints 7157-7162 of 8354")
	)
	(layers
		(0 "F.Cu" signal "TOP")
		(4 "In1.Cu" signal "GND")
		(6 "In2.Cu" signal "IN1")
		(8 "In3.Cu" signal "GND1")
		(10 "In4.Cu" signal "IN2")
		(12 "In5.Cu" signal "GND2")
		(14 "In6.Cu" signal "IN3")
		(16 "In7.Cu" signal "GND3")
		(18 "In8.Cu" signal "VCC")
		(20 "In9.Cu" signal "VCC1")
		(22 "In10.Cu" signal "GND4")
		(24 "In11.Cu" signal "IN4")
		(26 "In12.Cu" signal "GND5")
		(28 "In13.Cu" signal "IN5")
		(30 "In14.Cu" signal "GND6")
		(32 "In15.Cu" signal "IN6")
		(34 "In16.Cu" signal "GND7")
		(2 "B.Cu" signal "BOTTOM")
		(9 "F.Adhes" user "F.Adhesive")
		(11 "B.Adhes" user "B.Adhesive")
		(13 "F.Paste" user "Package Geometry/Pastemask Top")
		(15 "B.Paste" user "Package Geometry/Pastemask Bottom")
		(5 "F.SilkS" user "Ref Des/Silkscreen Top")
		(7 "B.SilkS" user "Ref Des/Silkscreen Bottom")
		(1 "F.Mask" user "Board Geometry/Soldermask Top")
		(3 "B.Mask" user "Board Geometry/Soldermask Bottom")
		(17 "Dwgs.User" user "User.Drawings")
		(19 "Cmts.User" user "User.Comments")
		(21 "Eco1.User" user "User.Eco1")
		(23 "Eco2.User" user "User.Eco2")
		(25 "Edge.Cuts" user "Board Geometry/Outline")
		(27 "Margin" user)
		(31 "F.CrtYd" user "Package Geometry/Place Bound Top")
		(29 "B.CrtYd" user "Package Geometry/Place Bound Bottom")
		(35 "F.Fab" user "Ref Des/Assembly Top")
		(33 "B.Fab" user "Ref Des/Assembly Bottom")
	)
	(footprint ""
		(layer "B.Cu")
		(at 155.01239 -13.762228 90)
		(property "Reference" "R2414"
			(at 0 0 90)
			(layer "B.SilkS")
			(hide yes)
			(effects
				(font
					(size 1.27 1.27)
				)
				(justify mirror)
			)
		)
		(property "Value" ""
			(at 0 0 90)
			(layer "B.Fab")
			(effects
				(font
					(size 1.27 1.27)
				)
				(justify mirror)
			)
		)
		(duplicate_pad_numbers_are_jumpers no)
		(fp_line
			(start 0.7874 -0.4064)
			(end -0.7874 -0.4064)
			(stroke
				(width 0.1524)
				(type default)
			)
			(layer "B.SilkS")
		)
		(fp_line
			(start -0.7874 -0.4064)
			(end -0.7874 0.4064)
			(stroke
				(width 0.1524)
				(type default)
			)
			(layer "B.SilkS")
		)
		(fp_line
			(start 0.7874 0.4064)
			(end 0.7874 -0.4064)
			(stroke
				(width 0.1524)
				(type default)
			)
			(layer "B.SilkS")
		)
		(fp_line
			(start -0.7874 0.4064)
			(end 0.7874 0.4064)
			(stroke
				(width 0.1524)
				(type default)
			)
			(layer "B.SilkS")
		)
		(fp_line
			(start 0.67945 -0.305054)
			(end 0.12065 -0.305054)
			(stroke
				(width 0.1)
				(type default)
			)
			(layer "B.Fab")
		)
		(fp_line
			(start 0.12065 -0.305054)
			(end 0.12065 -0.2794)
			(stroke
				(width 0.1)
				(type default)
			)
			(layer "B.Fab")
		)
		(fp_line
			(start -0.12065 -0.3048)
			(end -0.67945 -0.3048)
			(stroke
				(width 0.1)
				(type default)
			)
			(layer "B.Fab")
		)
		(fp_line
			(start -0.67945 -0.3048)
			(end -0.67945 0.3048)
			(stroke
				(width 0.1)
				(type default)
			)
			(layer "B.Fab")
		)
		(fp_line
			(start 0.12065 -0.2794)
			(end -0.12065 -0.2794)
			(stroke
				(width 0.1)
				(type default)
			)
			(layer "B.Fab")
		)
		(fp_line
			(start -0.12065 -0.2794)
			(end -0.12065 -0.3048)
			(stroke
				(width 0.1)
				(type default)
			)
			(layer "B.Fab")
		)
		(fp_line
			(start 0.12065 0.2794)
			(end 0.12065 0.3048)
			(stroke
				(width 0.1)
				(type default)
			)
			(layer "B.Fab")
		)
		(fp_line
			(start -0.120396 0.2794)
			(end 0.12065 0.2794)
			(stroke
				(width 0.1)
				(type default)
			)
			(layer "B.Fab")
		)
		(fp_line
			(start 0.67945 0.3048)
			(end 0.67945 -0.305054)
			(stroke
				(width 0.1)
				(type default)
			)
			(layer "B.Fab")
		)
		(fp_line
			(start 0.12065 0.3048)
			(end 0.67945 0.3048)
			(stroke
				(width 0.1)
				(type default)
			)
			(layer "B.Fab")
		)
		(fp_line
			(start -0.120396 0.3048)
			(end -0.120396 0.2794)
			(stroke
				(width 0.1)
				(type default)
			)
			(layer "B.Fab")
		)
		(fp_line
			(start -0.67945 0.3048)
			(end -0.120396 0.3048)
			(stroke
				(width 0.1)
				(type default)
			)
			(layer "B.Fab")
		)
		(pad "1" smd circle
			(at 0.40005 0 270)
			(size 0 0)
			(layers "B.Cu" "B.Mask" "B.Paste")
			(net "SMB_2_BMC_GPU_SDA")
		)
		(pad "2" smd circle
			(at -0.40005 0 270)
			(size 0 0)
			(layers "B.Cu" "B.Mask" "B.Paste")
			(net "SMB_PCIE2_3V3AUX_SDA_R0")
		)
	)
	(footprint ""
		(layer "B.Cu")
		(at 320.846958 -198.583296)
		(property "Reference" "R408"
			(at 0 0 0)
			(layer "B.SilkS")
			(hide yes)
			(effects
				(font
					(size 1.27 1.27)
				)
				(justify mirror)
			)
		)
		(property "Value" ""
			(at 0 0 0)
			(layer "B.Fab")
			(effects
				(font
					(size 1.27 1.27)
				)
				(justify mirror)
			)
		)
		(duplicate_pad_numbers_are_jumpers no)
		(fp_line
			(start -0.7874 -0.4064)
			(end -0.7874 0.4064)
			(stroke
				(width 0.1524)
				(type default)
			)
			(layer "B.SilkS")
		)
		(fp_line
			(start -0.7874 0.4064)
			(end 0.7874 0.4064)
			(stroke
				(width 0.1524)
				(type default)
			)
			(layer "B.SilkS")
		)
		(fp_line
			(start 0.7874 -0.4064)
			(end -0.7874 -0.4064)
			(stroke
				(width 0.1524)
				(type default)
			)
			(layer "B.SilkS")
		)
		(fp_line
			(start 0.7874 0.4064)
			(end 0.7874 -0.4064)
			(stroke
				(width 0.1524)
				(type default)
			)
			(layer "B.SilkS")
		)
		(fp_line
			(start -0.67945 -0.3048)
			(end -0.67945 0.3048)
			(stroke
				(width 0.1)
				(type default)
			)
			(layer "B.Fab")
		)
		(fp_line
			(start -0.67945 0.3048)
			(end -0.120396 0.3048)
			(stroke
				(width 0.1)
				(type default)
			)
			(layer "B.Fab")
		)
		(fp_line
			(start -0.12065 -0.3048)
			(end -0.67945 -0.3048)
			(stroke
				(width 0.1)
				(type default)
			)
			(layer "B.Fab")
		)
		(fp_line
			(start -0.12065 -0.2794)
			(end -0.12065 -0.3048)
			(stroke
				(width 0.1)
				(type default)
			)
			(layer "B.Fab")
		)
		(fp_line
			(start -0.120396 0.2794)
			(end 0.12065 0.2794)
			(stroke
				(width 0.1)
				(type default)
			)
			(layer "B.Fab")
		)
		(fp_line
			(start -0.120396 0.3048)
			(end -0.120396 0.2794)
			(stroke
				(width 0.1)
				(type default)
			)
			(layer "B.Fab")
		)
		(fp_line
			(start 0.12065 -0.305054)
			(end 0.12065 -0.2794)
			(stroke
				(width 0.1)
				(type default)
			)
			(layer "B.Fab")
		)
		(fp_line
			(start 0.12065 -0.2794)
			(end -0.12065 -0.2794)
			(stroke
				(width 0.1)
				(type default)
			)
			(layer "B.Fab")
		)
		(fp_line
			(start 0.12065 0.2794)
			(end 0.12065 0.3048)
			(stroke
				(width 0.1)
				(type default)
			)
			(layer "B.Fab")
		)
		(fp_line
			(start 0.12065 0.3048)
			(end 0.67945 0.3048)
			(stroke
				(width 0.1)
				(type default)
			)
			(layer "B.Fab")
		)
		(fp_line
			(start 0.67945 -0.305054)
			(end 0.12065 -0.305054)
			(stroke
				(width 0.1)
				(type default)
			)
			(layer "B.Fab")
		)
		(fp_line
			(start 0.67945 0.3048)
			(end 0.67945 -0.305054)
			(stroke
				(width 0.1)
				(type default)
			)
			(layer "B.Fab")
		)
		(pad "1" smd circle
			(at 0.40005 0 180)
			(size 0 0)
			(layers "B.Cu" "B.Mask" "B.Paste")
			(net "CPU0_BP0")
		)
		(pad "2" smd circle
			(at -0.40005 0 180)
			(size 0 0)
			(layers "B.Cu" "B.Mask" "B.Paste")
			(net "PVDD18_S5_P0")
		)
	)
	(footprint ""
		(layer "B.Cu")
		(at 108.833158 -408.52598)
		(property "Reference" "C58"
			(at 0 0 0)
			(layer "B.SilkS")
			(hide yes)
			(effects
				(font
					(size 1.27 1.27)
				)
				(justify mirror)
			)
		)
		(property "Value" ""
			(at 0 0 0)
			(layer "B.Fab")
			(effects
				(font
					(size 1.27 1.27)
				)
				(justify mirror)
			)
		)
		(duplicate_pad_numbers_are_jumpers no)
		(fp_line
			(start -0.7874 -0.4064)
			(end -0.7874 0.4064)
			(stroke
				(width 0.1524)
				(type default)
			)
			(layer "B.SilkS")
		)
		(fp_line
			(start -0.7874 0.4064)
			(end 0.7874 0.4064)
			(stroke
				(width 0.1524)
				(type default)
			)
			(layer "B.SilkS")
		)
		(fp_line
			(start 0.7874 -0.4064)
			(end -0.7874 -0.4064)
			(stroke
				(width 0.1524)
				(type default)
			)
			(layer "B.SilkS")
		)
		(fp_line
			(start 0.7874 0.4064)
			(end 0.7874 -0.4064)
			(stroke
				(width 0.1524)
				(type default)
			)
			(layer "B.SilkS")
		)
		(fp_line
			(start -0.67945 -0.3048)
			(end -0.67945 0.3048)
			(stroke
				(width 0.1)
				(type default)
			)
			(layer "B.Fab")
		)
		(fp_line
			(start -0.67945 0.3048)
			(end -0.120396 0.3048)
			(stroke
				(width 0.1)
				(type default)
			)
			(layer "B.Fab")
		)
		(fp_line
			(start -0.12065 -0.3048)
			(end -0.67945 -0.3048)
			(stroke
				(width 0.1)
				(type default)
			)
			(layer "B.Fab")
		)
		(fp_line
			(start -0.12065 -0.2794)
			(end -0.12065 -0.3048)
			(stroke
				(width 0.1)
				(type default)
			)
			(layer "B.Fab")
		)
		(fp_line
			(start -0.120396 0.2794)
			(end 0.12065 0.2794)
			(stroke
				(width 0.1)
				(type default)
			)
			(layer "B.Fab")
		)
		(fp_line
			(start -0.120396 0.3048)
			(end -0.120396 0.2794)
			(stroke
				(width 0.1)
				(type default)
			)
			(layer "B.Fab")
		)
		(fp_line
			(start 0.12065 -0.305054)
			(end 0.12065 -0.2794)
			(stroke
				(width 0.1)
				(type default)
			)
			(layer "B.Fab")
		)
		(fp_line
			(start 0.12065 -0.2794)
			(end -0.12065 -0.2794)
			(stroke
				(width 0.1)
				(type default)
			)
			(layer "B.Fab")
		)
		(fp_line
			(start 0.12065 0.2794)
			(end 0.12065 0.3048)
			(stroke
				(width 0.1)
				(type default)
			)
			(layer "B.Fab")
		)
		(fp_line
			(start 0.12065 0.3048)
			(end 0.67945 0.3048)
			(stroke
				(width 0.1)
				(type default)
			)
			(layer "B.Fab")
		)
		(fp_line
			(start 0.67945 -0.305054)
			(end 0.12065 -0.305054)
			(stroke
				(width 0.1)
				(type default)
			)
			(layer "B.Fab")
		)
		(fp_line
			(start 0.67945 0.3048)
			(end 0.67945 -0.305054)
			(stroke
				(width 0.1)
				(type default)
			)
			(layer "B.Fab")
		)
		(pad "1" smd circle
			(at 0.40005 0 180)
			(size 0 0)
			(layers "B.Cu" "B.Mask" "B.Paste")
			(net "P3V3_9ZXL045_P1_VDD")
		)
		(pad "2" smd circle
			(at -0.40005 0 180)
			(size 0 0)
			(layers "B.Cu" "B.Mask" "B.Paste")
			(net "GND")
		)
	)
	(footprint ""
		(layer "B.Cu")
		(at 157.61843 -14.143228 180)
		(property "Reference" "R330"
			(at 0 0 0)
			(layer "B.SilkS")
			(hide yes)
			(effects
				(font
					(size 1.27 1.27)
				)
				(justify mirror)
			)
		)
		(property "Value" ""
			(at 0 0 0)
			(layer "B.Fab")
			(effects
				(font
					(size 1.27 1.27)
				)
				(justify mirror)
			)
		)
		(duplicate_pad_numbers_are_jumpers no)
		(fp_line
			(start 0.7874 0.4064)
			(end 0.7874 -0.4064)
			(stroke
				(width 0.1524)
				(type default)
			)
			(layer "B.SilkS")
		)
		(fp_line
			(start 0.7874 -0.4064)
			(end -0.7874 -0.4064)
			(stroke
				(width 0.1524)
				(type default)
			)
			(layer "B.SilkS")
		)
		(fp_line
			(start -0.7874 0.4064)
			(end 0.7874 0.4064)
			(stroke
				(width 0.1524)
				(type default)
			)
			(layer "B.SilkS")
		)
		(fp_line
			(start -0.7874 -0.4064)
			(end -0.7874 0.4064)
			(stroke
				(width 0.1524)
				(type default)
			)
			(layer "B.SilkS")
		)
		(fp_line
			(start 0.67945 0.3048)
			(end 0.67945 -0.305054)
			(stroke
				(width 0.1)
				(type default)
			)
			(layer "B.Fab")
		)
		(fp_line
			(start 0.67945 -0.305054)
			(end 0.12065 -0.305054)
			(stroke
				(width 0.1)
				(type default)
			)
			(layer "B.Fab")
		)
		(fp_line
			(start 0.12065 0.3048)
			(end 0.67945 0.3048)
			(stroke
				(width 0.1)
				(type default)
			)
			(layer "B.Fab")
		)
		(fp_line
			(start 0.12065 0.2794)
			(end 0.12065 0.3048)
			(stroke
				(width 0.1)
				(type default)
			)
			(layer "B.Fab")
		)
		(fp_line
			(start 0.12065 -0.2794)
			(end -0.12065 -0.2794)
			(stroke
				(width 0.1)
				(type default)
			)
			(layer "B.Fab")
		)
		(fp_line
			(start 0.12065 -0.305054)
			(end 0.12065 -0.2794)
			(stroke
				(width 0.1)
				(type default)
			)
			(layer "B.Fab")
		)
		(fp_line
			(start -0.120396 0.3048)
			(end -0.120396 0.2794)
			(stroke
				(width 0.1)
				(type default)
			)
			(layer "B.Fab")
		)
		(fp_line
			(start -0.120396 0.2794)
			(end 0.12065 0.2794)
			(stroke
				(width 0.1)
				(type default)
			)
			(layer "B.Fab")
		)
		(fp_line
			(start -0.12065 -0.2794)
			(end -0.12065 -0.3048)
			(stroke
				(width 0.1)
				(type default)
			)
			(layer "B.Fab")
		)
		(fp_line
			(start -0.12065 -0.3048)
			(end -0.67945 -0.3048)
			(stroke
				(width 0.1)
				(type default)
			)
			(layer "B.Fab")
		)
		(fp_line
			(start -0.67945 0.3048)
			(end -0.120396 0.3048)
			(stroke
				(width 0.1)
				(type default)
			)
			(layer "B.Fab")
		)
		(fp_line
			(start -0.67945 -0.3048)
			(end -0.67945 0.3048)
			(stroke
				(width 0.1)
				(type default)
			)
			(layer "B.Fab")
		)
		(pad "1" smd circle
			(at 0.40005 0)
			(size 0 0)
			(layers "B.Cu" "B.Mask" "B.Paste")
			(net "SMB_FAN_3V3AUX_SCL")
		)
		(pad "2" smd circle
			(at -0.40005 0)
			(size 0 0)
			(layers "B.Cu" "B.Mask" "B.Paste")
			(net "P3V3_AUX")
		)
	)
	(footprint ""
		(layer "B.Cu")
		(at 242.697 -229.489 180)
		(property "Reference" "R368"
			(at 0 0 0)
			(layer "B.SilkS")
			(hide yes)
			(effects
				(font
					(size 1.27 1.27)
				)
				(justify mirror)
			)
		)
		(property "Value" ""
			(at 0 0 0)
			(layer "B.Fab")
			(effects
				(font
					(size 1.27 1.27)
				)
				(justify mirror)
			)
		)
		(duplicate_pad_numbers_are_jumpers no)
		(fp_line
			(start 0.7874 0.4064)
			(end 0.7874 -0.4064)
			(stroke
				(width 0.1524)
				(type default)
			)
			(layer "B.SilkS")
		)
		(fp_line
			(start 0.7874 -0.4064)
			(end -0.7874 -0.4064)
			(stroke
				(width 0.1524)
				(type default)
			)
			(layer "B.SilkS")
		)
		(fp_line
			(start -0.7874 0.4064)
			(end 0.7874 0.4064)
			(stroke
				(width 0.1524)
				(type default)
			)
			(layer "B.SilkS")
		)
		(fp_line
			(start -0.7874 -0.4064)
			(end -0.7874 0.4064)
			(stroke
				(width 0.1524)
				(type default)
			)
			(layer "B.SilkS")
		)
		(fp_line
			(start 0.67945 0.3048)
			(end 0.67945 -0.305054)
			(stroke
				(width 0.1)
				(type default)
			)
			(layer "B.Fab")
		)
		(fp_line
			(start 0.67945 -0.305054)
			(end 0.12065 -0.305054)
			(stroke
				(width 0.1)
				(type default)
			)
			(layer "B.Fab")
		)
		(fp_line
			(start 0.12065 0.3048)
			(end 0.67945 0.3048)
			(stroke
				(width 0.1)
				(type default)
			)
			(layer "B.Fab")
		)
		(fp_line
			(start 0.12065 0.2794)
			(end 0.12065 0.3048)
			(stroke
				(width 0.1)
				(type default)
			)
			(layer "B.Fab")
		)
		(fp_line
			(start 0.12065 -0.2794)
			(end -0.12065 -0.2794)
			(stroke
				(width 0.1)
				(type default)
			)
			(layer "B.Fab")
		)
		(fp_line
			(start 0.12065 -0.305054)
			(end 0.12065 -0.2794)
			(stroke
				(width 0.1)
				(type default)
			)
			(layer "B.Fab")
		)
		(fp_line
			(start -0.120396 0.3048)
			(end -0.120396 0.2794)
			(stroke
				(width 0.1)
				(type default)
			)
			(layer "B.Fab")
		)
		(fp_line
			(start -0.120396 0.2794)
			(end 0.12065 0.2794)
			(stroke
				(width 0.1)
				(type default)
			)
			(layer "B.Fab")
		)
		(fp_line
			(start -0.12065 -0.2794)
			(end -0.12065 -0.3048)
			(stroke
				(width 0.1)
				(type default)
			)
			(layer "B.Fab")
		)
		(fp_line
			(start -0.12065 -0.3048)
			(end -0.67945 -0.3048)
			(stroke
				(width 0.1)
				(type default)
			)
			(layer "B.Fab")
		)
		(fp_line
			(start -0.67945 0.3048)
			(end -0.120396 0.3048)
			(stroke
				(width 0.1)
				(type default)
			)
			(layer "B.Fab")
		)
		(fp_line
			(start -0.67945 -0.3048)
			(end -0.67945 0.3048)
			(stroke
				(width 0.1)
				(type default)
			)
			(layer "B.Fab")
		)
		(pad "1" smd circle
			(at 0.40005 0)
			(size 0 0)
			(layers "B.Cu" "B.Mask" "B.Paste")
			(net "PVDD18_S5_P0")
		)
		(pad "2" smd circle
			(at -0.40005 0)
			(size 0 0)
			(layers "B.Cu" "B.Mask" "B.Paste")
			(net "SMB_CPU0_CPU1_SEC_SCL_R2")
		)
	)
	(footprint ""
		(layer "B.Cu")
		(at 186.81446 -190.948564 180)
		(property "Reference" "R312"
			(at 0 0 0)
			(layer "B.SilkS")
			(hide yes)
			(effects
				(font
					(size 1.27 1.27)
				)
				(justify mirror)
			)
		)
		(property "Value" ""
			(at 0 0 0)
			(layer "B.Fab")
			(effects
				(font
					(size 1.27 1.27)
				)
				(justify mirror)
			)
		)
		(duplicate_pad_numbers_are_jumpers no)
		(fp_line
			(start 0.7874 0.4064)
			(end 0.7874 -0.4064)
			(stroke
				(width 0.1524)
				(type default)
			)
			(layer "B.SilkS")
		)
		(fp_line
			(start 0.7874 -0.4064)
			(end -0.7874 -0.4064)
			(stroke
				(width 0.1524)
				(type default)
			)
			(layer "B.SilkS")
		)
		(fp_line
			(start -0.7874 0.4064)
			(end 0.7874 0.4064)
			(stroke
				(width 0.1524)
				(type default)
			)
			(layer "B.SilkS")
		)
		(fp_line
			(start -0.7874 -0.4064)
			(end -0.7874 0.4064)
			(stroke
				(width 0.1524)
				(type default)
			)
			(layer "B.SilkS")
		)
		(fp_line
			(start 0.67945 0.3048)
			(end 0.67945 -0.305054)
			(stroke
				(width 0.1)
				(type default)
			)
			(layer "B.Fab")
		)
		(fp_line
			(start 0.67945 -0.305054)
			(end 0.12065 -0.305054)
			(stroke
				(width 0.1)
				(type default)
			)
			(layer "B.Fab")
		)
		(fp_line
			(start 0.12065 0.3048)
			(end 0.67945 0.3048)
			(stroke
				(width 0.1)
				(type default)
			)
			(layer "B.Fab")
		)
		(fp_line
			(start 0.12065 0.2794)
			(end 0.12065 0.3048)
			(stroke
				(width 0.1)
				(type default)
			)
			(layer "B.Fab")
		)
		(fp_line
			(start 0.12065 -0.2794)
			(end -0.12065 -0.2794)
			(stroke
				(width 0.1)
				(type default)
			)
			(layer "B.Fab")
		)
		(fp_line
			(start 0.12065 -0.305054)
			(end 0.12065 -0.2794)
			(stroke
				(width 0.1)
				(type default)
			)
			(layer "B.Fab")
		)
		(fp_line
			(start -0.120396 0.3048)
			(end -0.120396 0.2794)
			(stroke
				(width 0.1)
				(type default)
			)
			(layer "B.Fab")
		)
		(fp_line
			(start -0.120396 0.2794)
			(end 0.12065 0.2794)
			(stroke
				(width 0.1)
				(type default)
			)
			(layer "B.Fab")
		)
		(fp_line
			(start -0.12065 -0.2794)
			(end -0.12065 -0.3048)
			(stroke
				(width 0.1)
				(type default)
			)
			(layer "B.Fab")
		)
		(fp_line
			(start -0.12065 -0.3048)
			(end -0.67945 -0.3048)
			(stroke
				(width 0.1)
				(type default)
			)
			(layer "B.Fab")
		)
		(fp_line
			(start -0.67945 0.3048)
			(end -0.120396 0.3048)
			(stroke
				(width 0.1)
				(type default)
			)
			(layer "B.Fab")
		)
		(fp_line
			(start -0.67945 -0.3048)
			(end -0.67945 0.3048)
			(stroke
				(width 0.1)
				(type default)
			)
			(layer "B.Fab")
		)
		(pad "1" smd circle
			(at 0.40005 0)
			(size 0 0)
			(layers "B.Cu" "B.Mask" "B.Paste")
			(net "PWRGD_CHJ_CPU1_DIMM")
		)
		(pad "2" smd circle
			(at -0.40005 0)
			(size 0 0)
			(layers "B.Cu" "B.Mask" "B.Paste")
			(net "PWRGD_CHGL_CPU1")
		)
	)
)
